(kicad_pcb
	(version 20260206)
	(generator "pcbnew")
	(generator_version "10.0")
	(general
		(thickness 1.6)
		(legacy_teardrops no)
	)
	(paper "A4")
	(title_block
		(title "panther-plus-userver — 13130-1b_20150205.brd")
		(comment 1 "Honey Badger (Wiwynn) / footprint 282 of 1509 (U13), pads 120-237 of 1283")
	)
	(layers
		(0 "F.Cu" signal "TOP")
		(4 "In1.Cu" signal "L2")
		(6 "In2.Cu" signal "L3")
		(8 "In3.Cu" signal "L4")
		(10 "In4.Cu" signal "L5")
		(12 "In5.Cu" signal "L6")
		(14 "In6.Cu" signal "L7")
		(16 "In7.Cu" signal "L8")
		(18 "In8.Cu" signal "L9")
		(20 "In9.Cu" signal "L10")
		(22 "In10.Cu" signal "L11")
		(2 "B.Cu" signal "BOTTOM")
		(9 "F.Adhes" user "F.Adhesive")
		(11 "B.Adhes" user "B.Adhesive")
		(13 "F.Paste" user "Package Geometry/Pastemask Top")
		(15 "B.Paste" user "Package Geometry/Pastemask Bottom")
		(5 "F.SilkS" user "Ref Des/Silkscreen Top")
		(7 "B.SilkS" user "Ref Des/Silkscreen Bottom")
		(1 "F.Mask" user "Board Geometry/Soldermask Top")
		(3 "B.Mask" user "Board Geometry/Soldermask Bottom")
		(17 "Dwgs.User" user "User.Drawings")
		(19 "Cmts.User" user "User.Comments")
		(21 "Eco1.User" user "User.Eco1")
		(23 "Eco2.User" user "User.Eco2")
		(25 "Edge.Cuts" user "Board Geometry/Outline")
		(27 "Margin" user)
		(31 "F.CrtYd" user "Package Geometry/Place Bound Top")
		(29 "B.CrtYd" user "Package Geometry/Place Bound Bottom")
		(35 "F.Fab" user "Ref Des/Assembly Top")
		(33 "B.Fab" user "Ref Des/Assembly Bottom")
	)
	(footprint ""
		(layer "F.Cu")
		(at 95.849948 -39.200074 180)
		(property "Reference" "U13"
			(at 0 0 180)
			(layer "F.SilkS")
			(hide yes)
			(effects
				(font
					(size 1.27 1.27)
				)
			)
		)
		(property "Value" "AVOTON-GP"
			(at -25.0317 -2.4892 180)
			(unlocked yes)
			(layer "F.Fab")
			(hide yes)
			(effects
				(font
					(size 1.016 1.016)
					(thickness 0.1524)
				)
			)
		)
		(property "Device Type" "BGA1283M3428-3H197"
			(at -25.0317 -4.0132 180)
			(unlocked yes)
			(layer "F.Fab")
			(hide yes)
			(effects
				(font
					(size 1.016 1.016)
					(thickness 0.1524)
				)
			)
		)
		(duplicate_pad_numbers_are_jumpers no)
		(pad "AD50" smd circle
			(at 8.39216 -1.75514 180)
			(size 0.3048 0.3048)
			(layers "F.Cu" "F.Mask" "F.Paste")
			(net "XDP_BUF_RTEST#")
		)
		(pad "AD52" smd circle
			(at 9.15416 -1.75514 180)
			(size 0.3048 0.3048)
			(layers "F.Cu" "F.Mask" "F.Paste")
			(net "GND")
		)
		(pad "AD53" smd circle
			(at 9.91616 -1.75514 180)
			(size 0.3048 0.3048)
			(layers "F.Cu" "F.Mask" "F.Paste")
			(net "PU_INTRUDER#")
		)
		(pad "AD55" smd circle
			(at 10.67816 -1.75514 180)
			(size 0.3048 0.3048)
			(layers "F.Cu" "F.Mask" "F.Paste")
			(net "RTC_EXTPAD")
		)
		(pad "AD56" smd circle
			(at 11.44016 -1.75514 180)
			(size 0.3048 0.3048)
			(layers "F.Cu" "F.Mask" "F.Paste")
			(net "GND")
		)
		(pad "AD58" smd circle
			(at 12.20216 -1.75514 180)
			(size 0.3048 0.3048)
			(layers "F.Cu" "F.Mask" "F.Paste")
			(net "PMU_SUS_CLK_CPU")
		)
		(pad "AD59" smd circle
			(at 12.96416 -1.75514 180)
			(size 0.3048 0.3048)
			(layers "F.Cu" "F.Mask" "F.Paste")
			(net "SPI_CPU_MISO")
		)
		(pad "AD62" smd circle
			(at 14.20368 -1.9939 180)
			(size 0.3048 0.3048)
			(layers "F.Cu" "F.Mask" "F.Paste")
			(net "GND")
		)
		(pad "AD63" smd circle
			(at 14.89964 -1.89738 180)
			(size 0.3048 0.3048)
			(layers "F.Cu" "F.Mask" "F.Paste")
			(net "USB_OC#")
		)
		(pad "AD65" smd circle
			(at 15.64132 -1.8923 180)
			(size 0.3048 0.3048)
			(layers "F.Cu" "F.Mask" "F.Paste")
			(net "XDP_SOC_CPU_TCK")
		)
		(pad "AD66" smd oval
			(at 16.24838 -1.54178 180)
			(size 0.3429 0.254)
			(layers "F.Cu" "F.Mask" "F.Paste")
			(net "PMU_WAKE#")
		)
		(pad "AE1" smd oval
			(at -16.24838 -1.33604 180)
			(size 0.3429 0.254)
			(layers "F.Cu" "F.Mask" "F.Paste")
			(net "PVCCP")
		)
		(pad "AE3" smd circle
			(at -15.24254 -1.1049 180)
			(size 0.3048 0.3048)
			(layers "F.Cu" "F.Mask" "F.Paste")
			(net "AVV_VCCCPUVIDSIO_1P03_SENSE")
		)
		(pad "AE5" smd circle
			(at -14.08176 -1.11506 180)
			(size 0.3048 0.3048)
			(layers "F.Cu" "F.Mask" "F.Paste")
			(net "PVCCP")
		)
		(pad "AE47" smd circle
			(at 6.84276 -1.05664 180)
			(size 0.3048 0.3048)
			(layers "F.Cu" "F.Mask" "F.Paste")
			(net "GND")
		)
		(pad "AE62" smd circle
			(at 14.01318 -1.31572 180)
			(size 0.3048 0.3048)
			(layers "F.Cu" "F.Mask" "F.Paste")
			(net "PMU_PLTRST_R#")
		)
		(pad "AE64" smd circle
			(at 15.24762 -1.28524 180)
			(size 0.3048 0.3048)
			(layers "F.Cu" "F.Mask" "F.Paste")
			(net "GND")
		)
		(pad "AF2" smd circle
			(at -15.75308 -0.61722 180)
			(size 0.3048 0.3048)
			(layers "F.Cu" "F.Mask" "F.Paste")
			(net "AVV_VSSCPUVIDSIO_1P03_SENSE")
		)
		(pad "AF4" smd circle
			(at -14.7955 -0.56388 180)
			(size 0.3048 0.3048)
			(layers "F.Cu" "F.Mask" "F.Paste")
			(net "PVCCP")
		)
		(pad "AF20" smd circle
			(at -6.84276 -0.81534 180)
			(size 0.3048 0.3048)
			(layers "F.Cu" "F.Mask" "F.Paste")
			(net "PVCCP")
		)
		(pad "AF21" smd circle
			(at -5.99948 -0.8001 180)
			(size 0.381 0.381)
			(layers "F.Cu" "F.Mask" "F.Paste")
			(net "PVCCP")
		)
		(pad "AF23" smd circle
			(at -5.20192 -0.8001 180)
			(size 0.381 0.381)
			(layers "F.Cu" "F.Mask" "F.Paste")
			(net "PVCCP")
		)
		(pad "AF25" smd circle
			(at -4.39928 -0.8001 180)
			(size 0.381 0.381)
			(layers "F.Cu" "F.Mask" "F.Paste")
			(net "PVCCP")
		)
		(pad "AF26" smd circle
			(at -3.60172 -0.8001 180)
			(size 0.381 0.381)
			(layers "F.Cu" "F.Mask" "F.Paste")
			(net "PVCCP")
		)
		(pad "AF28" smd circle
			(at -2.79908 -0.8001 180)
			(size 0.381 0.381)
			(layers "F.Cu" "F.Mask" "F.Paste")
			(net "GND")
		)
		(pad "AF29" smd circle
			(at -2.00152 -0.8001 180)
			(size 0.381 0.381)
			(layers "F.Cu" "F.Mask" "F.Paste")
			(net "P1V1")
		)
		(pad "AF31" smd circle
			(at -1.19888 -0.8001 180)
			(size 0.381 0.381)
			(layers "F.Cu" "F.Mask" "F.Paste")
			(net "P1V1")
		)
		(pad "AF32" smd circle
			(at -0.40132 -0.8001 180)
			(size 0.381 0.381)
			(layers "F.Cu" "F.Mask" "F.Paste")
			(net "VCCRAMCPUSI1_SENSE")
		)
		(pad "AF34" smd circle
			(at 0.40132 -0.8001 180)
			(size 0.381 0.381)
			(layers "F.Cu" "F.Mask" "F.Paste")
			(net "VSSRAMCPUSI1_SENSE")
		)
		(pad "AF36" smd circle
			(at 1.19888 -0.8001 180)
			(size 0.381 0.381)
			(layers "F.Cu" "F.Mask" "F.Paste")
			(net "PVNN")
		)
		(pad "AF38" smd circle
			(at 2.00152 -0.8001 180)
			(size 0.381 0.381)
			(layers "F.Cu" "F.Mask" "F.Paste")
			(net "P1V0")
		)
		(pad "AF39" smd circle
			(at 2.79908 -0.8001 180)
			(size 0.381 0.381)
			(layers "F.Cu" "F.Mask" "F.Paste")
			(net "PVNN")
		)
		(pad "AF41" smd circle
			(at 3.60172 -0.8001 180)
			(size 0.381 0.381)
			(layers "F.Cu" "F.Mask" "F.Paste")
			(net "P1V8_STBY")
		)
		(pad "AF42" smd circle
			(at 4.39928 -0.8001 180)
			(size 0.381 0.381)
			(layers "F.Cu" "F.Mask" "F.Paste")
			(net "P1V8_STBY")
		)
		(pad "AF44" smd circle
			(at 5.20192 -0.8001 180)
			(size 0.381 0.381)
			(layers "F.Cu" "F.Mask" "F.Paste")
			(net "GND")
		)
		(pad "AF46" smd circle
			(at 5.99948 -0.8001 180)
			(size 0.381 0.381)
			(layers "F.Cu" "F.Mask" "F.Paste")
			(net "SPI_CPU_SCLK")
		)
		(pad "AF62" smd circle
			(at 14.06398 -0.61468 180)
			(size 0.3048 0.3048)
			(layers "F.Cu" "F.Mask" "F.Paste")
			(net "GND")
		)
		(pad "AF63" smd circle
			(at 14.75232 -0.78232 180)
			(size 0.3048 0.3048)
			(layers "F.Cu" "F.Mask" "F.Paste")
			(net "XDP_SOC_CPU_TDO")
		)
		(pad "AF65" smd circle
			(at 15.80642 -0.8636 180)
			(size 0.3048 0.3048)
			(layers "F.Cu" "F.Mask" "F.Paste")
			(net "PMU_SLP_S3#")
		)
		(pad "AG5" smd circle
			(at -14.06398 -0.4064 180)
			(size 0.3048 0.3048)
			(layers "F.Cu" "F.Mask" "F.Paste")
			(net "GND")
		)
		(pad "AG7" smd circle
			(at -13.34516 -0.23114 180)
			(size 0.3048 0.3048)
			(layers "F.Cu" "F.Mask" "F.Paste")
			(net "PVCCP")
		)
		(pad "AG8" smd circle
			(at -12.58316 -0.23114 180)
			(size 0.3048 0.3048)
			(layers "F.Cu" "F.Mask" "F.Paste")
			(net "PVCCP")
		)
		(pad "AG10" smd circle
			(at -11.82116 -0.23114 180)
			(size 0.3048 0.3048)
			(layers "F.Cu" "F.Mask" "F.Paste")
			(net "GND")
		)
		(pad "AG11" smd circle
			(at -11.05916 -0.23114 180)
			(size 0.3048 0.3048)
			(layers "F.Cu" "F.Mask" "F.Paste")
			(net "PVCCP")
		)
		(pad "AG13" smd circle
			(at -10.29716 -0.23114 180)
			(size 0.3048 0.3048)
			(layers "F.Cu" "F.Mask" "F.Paste")
			(net "PVCCP")
		)
		(pad "AG14" smd circle
			(at -9.53516 -0.23114 180)
			(size 0.3048 0.3048)
			(layers "F.Cu" "F.Mask" "F.Paste")
			(net "PVCCP")
		)
		(pad "AG16" smd circle
			(at -8.77316 -0.23114 180)
			(size 0.3048 0.3048)
			(layers "F.Cu" "F.Mask" "F.Paste")
			(net "GND")
		)
		(pad "AG17" smd circle
			(at -8.01116 -0.23114 180)
			(size 0.3048 0.3048)
			(layers "F.Cu" "F.Mask" "F.Paste")
			(net "PVCCP")
		)
		(pad "AG19" smd circle
			(at -7.24916 -0.23114 180)
			(size 0.3048 0.3048)
			(layers "F.Cu" "F.Mask" "F.Paste")
			(net "PVCCP")
		)
		(pad "AG21" smd circle
			(at -5.99948 0 180)
			(size 0.381 0.381)
			(layers "F.Cu" "F.Mask" "F.Paste")
			(net "PVCCP")
		)
		(pad "AG23" smd circle
			(at -5.20192 0 180)
			(size 0.381 0.381)
			(layers "F.Cu" "F.Mask" "F.Paste")
			(net "GND")
		)
		(pad "AG25" smd circle
			(at -4.39928 0 180)
			(size 0.381 0.381)
			(layers "F.Cu" "F.Mask" "F.Paste")
			(net "GND")
		)
		(pad "AG26" smd circle
			(at -3.60172 0 180)
			(size 0.381 0.381)
			(layers "F.Cu" "F.Mask" "F.Paste")
			(net "GND")
		)
		(pad "AG28" smd circle
			(at -2.79908 0 180)
			(size 0.381 0.381)
			(layers "F.Cu" "F.Mask" "F.Paste")
			(net "GND")
		)
		(pad "AG29" smd circle
			(at -2.00152 0 180)
			(size 0.381 0.381)
			(layers "F.Cu" "F.Mask" "F.Paste")
			(net "P1V1")
		)
		(pad "AG31" smd circle
			(at -1.19888 0 180)
			(size 0.381 0.381)
			(layers "F.Cu" "F.Mask" "F.Paste")
			(net "P1V1")
		)
		(pad "AG32" smd circle
			(at -0.40132 0 180)
			(size 0.381 0.381)
			(layers "F.Cu" "F.Mask" "F.Paste")
			(net "P1V1")
		)
		(pad "AG34" smd circle
			(at 0.40132 0 180)
			(size 0.381 0.381)
			(layers "F.Cu" "F.Mask" "F.Paste")
			(net "GND")
		)
		(pad "AG36" smd circle
			(at 1.19888 0 180)
			(size 0.381 0.381)
			(layers "F.Cu" "F.Mask" "F.Paste")
			(net "PVNN")
		)
		(pad "AG38" smd circle
			(at 2.00152 0 180)
			(size 0.381 0.381)
			(layers "F.Cu" "F.Mask" "F.Paste")
			(net "P1V0")
		)
		(pad "AG39" smd circle
			(at 2.79908 0 180)
			(size 0.381 0.381)
			(layers "F.Cu" "F.Mask" "F.Paste")
			(net "PVNN")
		)
		(pad "AG41" smd circle
			(at 3.60172 0 180)
			(size 0.381 0.381)
			(layers "F.Cu" "F.Mask" "F.Paste")
			(net "GND")
		)
		(pad "AG42" smd circle
			(at 4.39928 0 180)
			(size 0.381 0.381)
			(layers "F.Cu" "F.Mask" "F.Paste")
			(net "P3V3_RTC")
		)
		(pad "AG44" smd circle
			(at 5.20192 0 180)
			(size 0.381 0.381)
			(layers "F.Cu" "F.Mask" "F.Paste")
			(net "GND")
		)
		(pad "AG46" smd circle
			(at 5.99948 0 180)
			(size 0.381 0.381)
			(layers "F.Cu" "F.Mask" "F.Paste")
			(net "RCOMP_CORE_LVT")
		)
		(pad "AG48" smd circle
			(at 7.24916 -0.4699 180)
			(size 0.3048 0.3048)
			(layers "F.Cu" "F.Mask" "F.Paste")
			(net "GND")
		)
		(pad "AG50" smd circle
			(at 8.01116 -0.4699 180)
			(size 0.3048 0.3048)
			(layers "F.Cu" "F.Mask" "F.Paste")
			(net "CPU_UART_RXD_R")
		)
		(pad "AG51" smd circle
			(at 8.77316 -0.4699 180)
			(size 0.3048 0.3048)
			(layers "F.Cu" "F.Mask" "F.Paste")
			(net "LPC_CPU_R_CLKOUT0")
		)
		(pad "AG53" smd circle
			(at 9.53516 -0.4699 180)
			(size 0.3048 0.3048)
			(layers "F.Cu" "F.Mask" "F.Paste")
			(net "GND")
		)
		(pad "AG54" smd circle
			(at 10.29716 -0.4699 180)
			(size 0.3048 0.3048)
			(layers "F.Cu" "F.Mask" "F.Paste")
			(net "LPC_CPU_LAD0")
		)
		(pad "AG56" smd circle
			(at 11.05916 -0.4699 180)
			(size 0.3048 0.3048)
			(layers "F.Cu" "F.Mask" "F.Paste")
			(net "FLEX_CLK_SE1")
		)
		(pad "AG57" smd circle
			(at 11.82116 -0.4699 180)
			(size 0.3048 0.3048)
			(layers "F.Cu" "F.Mask" "F.Paste")
			(net "GND")
		)
		(pad "AG59" smd circle
			(at 12.58316 -0.4699 180)
			(size 0.3048 0.3048)
			(layers "F.Cu" "F.Mask" "F.Paste")
			(net "LPC_CPU_LAD3")
		)
		(pad "AG60" smd circle
			(at 13.34516 -0.4699 180)
			(size 0.3048 0.3048)
			(layers "F.Cu" "F.Mask" "F.Paste")
			(net "CPU_RSVD10")
		)
		(pad "AG63" smd circle
			(at 14.5415 -0.10414 180)
			(size 0.3048 0.3048)
			(layers "F.Cu" "F.Mask" "F.Paste")
			(net "GND")
		)
		(pad "AG64" smd circle
			(at 15.3035 -0.05334 180)
			(size 0.3048 0.3048)
			(layers "F.Cu" "F.Mask" "F.Paste")
			(net "GND")
		)
		(pad "AG66" smd oval
			(at 16.24838 -0.10414 180)
			(size 0.3429 0.254)
			(layers "F.Cu" "F.Mask" "F.Paste")
			(net "GND")
		)
		(pad "AH1" smd oval
			(at -16.24838 0.10414 180)
			(size 0.3429 0.254)
			(layers "F.Cu" "F.Mask" "F.Paste")
			(net "PVCCP")
		)
		(pad "AH3" smd circle
			(at -15.3035 0.05334 180)
			(size 0.3048 0.3048)
			(layers "F.Cu" "F.Mask" "F.Paste")
			(net "PVCCP")
		)
		(pad "AH4" smd circle
			(at -14.5415 0.10414 180)
			(size 0.3048 0.3048)
			(layers "F.Cu" "F.Mask" "F.Paste")
			(net "PVCCP")
		)
		(pad "AH7" smd circle
			(at -13.34516 0.4699 180)
			(size 0.3048 0.3048)
			(layers "F.Cu" "F.Mask" "F.Paste")
			(net "PVCCP")
		)
		(pad "AH8" smd circle
			(at -12.58316 0.4699 180)
			(size 0.3048 0.3048)
			(layers "F.Cu" "F.Mask" "F.Paste")
			(net "PVCCP")
		)
		(pad "AH10" smd circle
			(at -11.82116 0.4699 180)
			(size 0.3048 0.3048)
			(layers "F.Cu" "F.Mask" "F.Paste")
			(net "PVCCP")
		)
		(pad "AH11" smd circle
			(at -11.05916 0.4699 180)
			(size 0.3048 0.3048)
			(layers "F.Cu" "F.Mask" "F.Paste")
			(net "GND")
		)
		(pad "AH13" smd circle
			(at -10.29716 0.4699 180)
			(size 0.3048 0.3048)
			(layers "F.Cu" "F.Mask" "F.Paste")
			(net "PVCCP")
		)
		(pad "AH14" smd circle
			(at -9.53516 0.4699 180)
			(size 0.3048 0.3048)
			(layers "F.Cu" "F.Mask" "F.Paste")
			(net "PVCCP")
		)
		(pad "AH16" smd circle
			(at -8.77316 0.4699 180)
			(size 0.3048 0.3048)
			(layers "F.Cu" "F.Mask" "F.Paste")
			(net "PVCCP")
		)
		(pad "AH17" smd circle
			(at -8.01116 0.4699 180)
			(size 0.3048 0.3048)
			(layers "F.Cu" "F.Mask" "F.Paste")
			(net "GND")
		)
		(pad "AH19" smd circle
			(at -7.24916 0.4699 180)
			(size 0.3048 0.3048)
			(layers "F.Cu" "F.Mask" "F.Paste")
			(net "PVCCP")
		)
		(pad "AH48" smd circle
			(at 7.24916 0.23114 180)
			(size 0.3048 0.3048)
			(layers "F.Cu" "F.Mask" "F.Paste")
			(net "LPC_CPU_CLKRUN#")
		)
		(pad "AH50" smd circle
			(at 8.01116 0.23114 180)
			(size 0.3048 0.3048)
			(layers "F.Cu" "F.Mask" "F.Paste")
			(net "CPU_UART_TXD_R")
		)
		(pad "AH51" smd circle
			(at 8.77316 0.23114 180)
			(size 0.3048 0.3048)
			(layers "F.Cu" "F.Mask" "F.Paste")
			(net "BD_ID_1")
		)
		(pad "AH53" smd circle
			(at 9.53516 0.23114 180)
			(size 0.3048 0.3048)
			(layers "F.Cu" "F.Mask" "F.Paste")
			(net "GND")
		)
		(pad "AH54" smd circle
			(at 10.29716 0.23114 180)
			(size 0.3048 0.3048)
			(layers "F.Cu" "F.Mask" "F.Paste")
			(net "CPU_DIAG_LED")
		)
		(pad "AH56" smd circle
			(at 11.05916 0.23114 180)
			(size 0.3048 0.3048)
			(layers "F.Cu" "F.Mask" "F.Paste")
			(net "LPC_CPU_FRAME#")
		)
		(pad "AH57" smd circle
			(at 11.82116 0.23114 180)
			(size 0.3048 0.3048)
			(layers "F.Cu" "F.Mask" "F.Paste")
			(net "GND")
		)
		(pad "AH59" smd circle
			(at 12.58316 0.23114 180)
			(size 0.3048 0.3048)
			(layers "F.Cu" "F.Mask" "F.Paste")
			(net "FLEX_CLK_SE0")
		)
		(pad "AH60" smd circle
			(at 13.34516 0.23114 180)
			(size 0.3048 0.3048)
			(layers "F.Cu" "F.Mask" "F.Paste")
			(net "CORE_PWROK_R")
		)
		(pad "AH62" smd circle
			(at 14.06398 0.4064 180)
			(size 0.3048 0.3048)
			(layers "F.Cu" "F.Mask" "F.Paste")
			(net "GND")
		)
		(pad "AJ2" smd circle
			(at -15.80642 0.8636 180)
			(size 0.3048 0.3048)
			(layers "F.Cu" "F.Mask" "F.Paste")
			(net "PVCCP")
		)
		(pad "AJ4" smd circle
			(at -14.75232 0.78232 180)
			(size 0.3048 0.3048)
			(layers "F.Cu" "F.Mask" "F.Paste")
			(net "PVCCP")
		)
		(pad "AJ5" smd circle
			(at -14.06398 0.61468 180)
			(size 0.3048 0.3048)
			(layers "F.Cu" "F.Mask" "F.Paste")
			(net "PVCCP")
		)
		(pad "AJ21" smd circle
			(at -5.99948 0.8001 180)
			(size 0.381 0.381)
			(layers "F.Cu" "F.Mask" "F.Paste")
			(net "PVCCP")
		)
		(pad "AJ23" smd circle
			(at -5.20192 0.8001 180)
			(size 0.381 0.381)
			(layers "F.Cu" "F.Mask" "F.Paste")
			(net "PVCCP")
		)
		(pad "AJ25" smd circle
			(at -4.39928 0.8001 180)
			(size 0.381 0.381)
			(layers "F.Cu" "F.Mask" "F.Paste")
			(net "PVCCP")
		)
		(pad "AJ26" smd circle
			(at -3.60172 0.8001 180)
			(size 0.381 0.381)
			(layers "F.Cu" "F.Mask" "F.Paste")
			(net "PVCCP")
		)
		(pad "AJ28" smd circle
			(at -2.79908 0.8001 180)
			(size 0.381 0.381)
			(layers "F.Cu" "F.Mask" "F.Paste")
			(net "GND")
		)
		(pad "AJ29" smd circle
			(at -2.00152 0.8001 180)
			(size 0.381 0.381)
			(layers "F.Cu" "F.Mask" "F.Paste")
			(net "P1V0")
		)
		(pad "AJ31" smd circle
			(at -1.19888 0.8001 180)
			(size 0.381 0.381)
			(layers "F.Cu" "F.Mask" "F.Paste")
			(net "VCCRAMCPUSI0GT_MOD3_1P03")
		)
		(pad "AJ32" smd circle
			(at -0.40132 0.8001 180)
			(size 0.381 0.381)
			(layers "F.Cu" "F.Mask" "F.Paste")
			(net "GND")
		)
		(pad "AJ34" smd circle
			(at 0.40132 0.8001 180)
			(size 0.381 0.381)
			(layers "F.Cu" "F.Mask" "F.Paste")
			(net "TP_CPU_RSVD9")
		)
		(pad "AJ36" smd circle
			(at 1.19888 0.8001 180)
			(size 0.381 0.381)
			(layers "F.Cu" "F.Mask" "F.Paste")
			(net "PVNN")
		)
		(pad "AJ38" smd circle
			(at 2.00152 0.8001 180)
			(size 0.381 0.381)
			(layers "F.Cu" "F.Mask" "F.Paste")
			(net "P1V0")
		)
		(pad "AJ39" smd circle
			(at 2.79908 0.8001 180)
			(size 0.381 0.381)
			(layers "F.Cu" "F.Mask" "F.Paste")
			(net "PVNN")
		)
		(pad "AJ41" smd circle
			(at 3.60172 0.8001 180)
			(size 0.381 0.381)
			(layers "F.Cu" "F.Mask" "F.Paste")
			(net "P1V8")
		)
		(pad "AJ42" smd circle
			(at 4.39928 0.8001 180)
			(size 0.381 0.381)
			(layers "F.Cu" "F.Mask" "F.Paste")
			(net "P3V3")
		)
		(pad "AJ44" smd circle
			(at 5.20192 0.8001 180)
			(size 0.381 0.381)
			(layers "F.Cu" "F.Mask" "F.Paste")
			(net "GND")
		)
		(pad "AJ46" smd circle
			(at 5.99948 0.8001 180)
			(size 0.381 0.381)
			(layers "F.Cu" "F.Mask" "F.Paste")
			(net "GND")
		)
	)
)
